(kicad_pcb
	(version 20260206)
	(generator "pcbnew")
	(generator_version "10.0")
	(general
		(thickness 1.6)
		(legacy_teardrops no)
	)
	(paper "A4")
	(title_block
		(title "Wiwynn_Tioga_Pass_MB.brd")
		(comment 1 "Tioga Pass / footprints 2933-2939 of 4770")
	)
	(layers
		(0 "F.Cu" signal "TOP")
		(4 "In1.Cu" signal "L2GND")
		(6 "In2.Cu" signal "L3")
		(8 "In3.Cu" signal "L4GND")
		(10 "In4.Cu" signal "L5")
		(12 "In5.Cu" signal "L6GND")
		(14 "In6.Cu" signal "L7VCC")
		(16 "In7.Cu" signal "L8VCC")
		(18 "In8.Cu" signal "L9GND")
		(20 "In9.Cu" signal "L10")
		(22 "In10.Cu" signal "L11GND")
		(24 "In11.Cu" signal "L12")
		(26 "In12.Cu" signal "L13GND")
		(2 "B.Cu" signal "BOTTOM")
		(9 "F.Adhes" user "F.Adhesive")
		(11 "B.Adhes" user "B.Adhesive")
		(13 "F.Paste" user "Package Geometry/Pastemask Top")
		(15 "B.Paste" user "Package Geometry/Pastemask Bottom")
		(5 "F.SilkS" user "Ref Des/Silkscreen Top")
		(7 "B.SilkS" user "Ref Des/Silkscreen Bottom")
		(1 "F.Mask" user "Board Geometry/Soldermask Top")
		(3 "B.Mask" user "Board Geometry/Soldermask Bottom")
		(17 "Dwgs.User" user "User.Drawings")
		(19 "Cmts.User" user "User.Comments")
		(21 "Eco1.User" user "User.Eco1")
		(23 "Eco2.User" user "User.Eco2")
		(25 "Edge.Cuts" user "Board Geometry/Outline")
		(27 "Margin" user)
		(31 "F.CrtYd" user "Package Geometry/Place Bound Top")
		(29 "B.CrtYd" user "Package Geometry/Place Bound Bottom")
		(35 "F.Fab" user "Ref Des/Assembly Top")
		(33 "B.Fab" user "Ref Des/Assembly Bottom")
	)
	(footprint ""
		(layer "B.Cu")
		(at 174.371 -65.024 -90)
		(property "Reference" "R6P49"
			(at 0 0 90)
			(layer "B.SilkS")
			(hide yes)
			(effects
				(font
					(size 1.27 1.27)
				)
				(justify mirror)
			)
		)
		(property "Value" ""
			(at 0 0 90)
			(layer "B.Fab")
			(effects
				(font
					(size 1.27 1.27)
				)
				(justify mirror)
			)
		)
		(duplicate_pad_numbers_are_jumpers no)
		(fp_poly
			(pts
				(xy 0.2794 -0.1016) (xy -0.2794 -0.1016) (xy -0.2794 0.9906) (xy 0.2794 0.9906)
			)
			(stroke
				(width 0)
				(type default)
			)
			(fill no)
			(layer "B.CrtYd")
		)
		(fp_line
			(start -0.2794 0.9906)
			(end -0.2794 -0.1016)
			(stroke
				(width 0.1)
				(type default)
			)
			(layer "B.Fab")
		)
		(fp_line
			(start 0.2794 0.9906)
			(end -0.2794 0.9906)
			(stroke
				(width 0.1)
				(type default)
			)
			(layer "B.Fab")
		)
		(fp_line
			(start -0.2794 -0.1016)
			(end 0.2794 -0.1016)
			(stroke
				(width 0.1)
				(type default)
			)
			(layer "B.Fab")
		)
		(fp_line
			(start 0.2794 -0.1016)
			(end 0.2794 0.9906)
			(stroke
				(width 0.1)
				(type default)
			)
			(layer "B.Fab")
		)
		(pad "1" smd rect
			(at 0 0 90)
			(size 0.508 0.508)
			(layers "B.Cu" "B.Mask" "B.Paste")
			(net "P3V3_STBY")
		)
		(pad "2" smd rect
			(at 0 0.889 90)
			(size 0.508 0.508)
			(layers "B.Cu" "B.Mask" "B.Paste")
			(net "PU_VR_PVCCIO_CPU1_FAULT1")
		)
		(zone
			(layer "B.Cu")
			(hatch none 0.5)
			(connect_pads
				(clearance 0)
			)
			(min_thickness 0.25)
			(keepout
				(tracks not_allowed)
				(vias allowed)
				(pads allowed)
				(copperpour not_allowed)
				(footprints allowed)
			)
			(placement
				(enabled no)
				(sheetname "")
			)
			(fill
				(thermal_gap 0.5)
				(thermal_bridge_width 0.5)
				(island_removal_mode 0)
			)
			(polygon
				(pts
					(xy 173.736 -64.77) (xy 173.736 -65.278) (xy 174.117 -65.278) (xy 174.117 -64.77)
				)
			)
		)
		(zone
			(layer "B.Cu")
			(hatch none 0.5)
			(connect_pads
				(clearance 0)
			)
			(min_thickness 0.25)
			(keepout
				(tracks allowed)
				(vias not_allowed)
				(pads allowed)
				(copperpour not_allowed)
				(footprints allowed)
			)
			(placement
				(enabled no)
				(sheetname "")
			)
			(fill
				(thermal_gap 0.5)
				(thermal_bridge_width 0.5)
				(island_removal_mode 0)
			)
			(polygon
				(pts
					(xy 174.117 -64.77) (xy 174.117 -65.278) (xy 173.736 -65.278) (xy 173.736 -64.77)
				)
			)
		)
	)
	(footprint ""
		(layer "B.Cu")
		(at 418.4142 -74.0537)
		(property "Reference" "R2T3"
			(at 0 0 0)
			(layer "B.SilkS")
			(hide yes)
			(effects
				(font
					(size 1.27 1.27)
				)
				(justify mirror)
			)
		)
		(property "Value" ""
			(at 0 0 0)
			(layer "B.Fab")
			(effects
				(font
					(size 1.27 1.27)
				)
				(justify mirror)
			)
		)
		(duplicate_pad_numbers_are_jumpers no)
		(fp_poly
			(pts
				(xy 0.2794 -0.1016) (xy -0.2794 -0.1016) (xy -0.2794 0.9906) (xy 0.2794 0.9906)
			)
			(stroke
				(width 0)
				(type default)
			)
			(fill no)
			(layer "B.CrtYd")
		)
		(fp_line
			(start -0.2794 -0.1016)
			(end 0.2794 -0.1016)
			(stroke
				(width 0.1)
				(type default)
			)
			(layer "B.Fab")
		)
		(fp_line
			(start -0.2794 0.9906)
			(end -0.2794 -0.1016)
			(stroke
				(width 0.1)
				(type default)
			)
			(layer "B.Fab")
		)
		(fp_line
			(start 0.2794 -0.1016)
			(end 0.2794 0.9906)
			(stroke
				(width 0.1)
				(type default)
			)
			(layer "B.Fab")
		)
		(fp_line
			(start 0.2794 0.9906)
			(end -0.2794 0.9906)
			(stroke
				(width 0.1)
				(type default)
			)
			(layer "B.Fab")
		)
		(pad "1" smd rect
			(at 0 0 180)
			(size 0.508 0.508)
			(layers "B.Cu" "B.Mask" "B.Paste")
			(net "P3V3_STBY")
		)
		(pad "2" smd rect
			(at 0 0.889 180)
			(size 0.508 0.508)
			(layers "B.Cu" "B.Mask" "B.Paste")
			(net "FM_FAST_PROCHOT_EN_N")
		)
		(zone
			(layer "B.Cu")
			(hatch none 0.5)
			(connect_pads
				(clearance 0)
			)
			(min_thickness 0.25)
			(keepout
				(tracks allowed)
				(vias not_allowed)
				(pads allowed)
				(copperpour not_allowed)
				(footprints allowed)
			)
			(placement
				(enabled no)
				(sheetname "")
			)
			(fill
				(thermal_gap 0.5)
				(thermal_bridge_width 0.5)
				(island_removal_mode 0)
			)
			(polygon
				(pts
					(xy 418.6682 -73.7997) (xy 418.1602 -73.7997) (xy 418.1602 -73.4187) (xy 418.6682 -73.4187)
				)
			)
		)
		(zone
			(layer "B.Cu")
			(hatch none 0.5)
			(connect_pads
				(clearance 0)
			)
			(min_thickness 0.25)
			(keepout
				(tracks not_allowed)
				(vias allowed)
				(pads allowed)
				(copperpour not_allowed)
				(footprints allowed)
			)
			(placement
				(enabled no)
				(sheetname "")
			)
			(fill
				(thermal_gap 0.5)
				(thermal_bridge_width 0.5)
				(island_removal_mode 0)
			)
			(polygon
				(pts
					(xy 418.6682 -73.4187) (xy 418.1602 -73.4187) (xy 418.1602 -73.7997) (xy 418.6682 -73.7997)
				)
			)
		)
	)
	(footprint ""
		(layer "B.Cu")
		(at 245.018306 -65.1764 -90)
		(property "Reference" "R5P4"
			(at 0 0 90)
			(layer "B.SilkS")
			(hide yes)
			(effects
				(font
					(size 1.27 1.27)
				)
				(justify mirror)
			)
		)
		(property "Value" ""
			(at 0 0 90)
			(layer "B.Fab")
			(effects
				(font
					(size 1.27 1.27)
				)
				(justify mirror)
			)
		)
		(duplicate_pad_numbers_are_jumpers no)
		(fp_poly
			(pts
				(xy 0.2794 -0.1016) (xy -0.2794 -0.1016) (xy -0.2794 0.9906) (xy 0.2794 0.9906)
			)
			(stroke
				(width 0)
				(type default)
			)
			(fill no)
			(layer "B.CrtYd")
		)
		(fp_line
			(start -0.2794 0.9906)
			(end -0.2794 -0.1016)
			(stroke
				(width 0.1)
				(type default)
			)
			(layer "B.Fab")
		)
		(fp_line
			(start 0.2794 0.9906)
			(end -0.2794 0.9906)
			(stroke
				(width 0.1)
				(type default)
			)
			(layer "B.Fab")
		)
		(fp_line
			(start -0.2794 -0.1016)
			(end 0.2794 -0.1016)
			(stroke
				(width 0.1)
				(type default)
			)
			(layer "B.Fab")
		)
		(fp_line
			(start 0.2794 -0.1016)
			(end 0.2794 0.9906)
			(stroke
				(width 0.1)
				(type default)
			)
			(layer "B.Fab")
		)
		(pad "1" smd rect
			(at 0 0 90)
			(size 0.508 0.508)
			(layers "B.Cu" "B.Mask" "B.Paste")
			(net "PD_CPU0_RSVD_TEST_2")
		)
		(pad "2" smd rect
			(at 0 0.889 90)
			(size 0.508 0.508)
			(layers "B.Cu" "B.Mask" "B.Paste")
			(net "GND")
		)
		(zone
			(layer "B.Cu")
			(hatch none 0.5)
			(connect_pads
				(clearance 0)
			)
			(min_thickness 0.25)
			(keepout
				(tracks not_allowed)
				(vias allowed)
				(pads allowed)
				(copperpour not_allowed)
				(footprints allowed)
			)
			(placement
				(enabled no)
				(sheetname "")
			)
			(fill
				(thermal_gap 0.5)
				(thermal_bridge_width 0.5)
				(island_removal_mode 0)
			)
			(polygon
				(pts
					(xy 244.383306 -64.9224) (xy 244.383306 -65.4304) (xy 244.764306 -65.4304) (xy 244.764306 -64.9224)
				)
			)
		)
		(zone
			(layer "B.Cu")
			(hatch none 0.5)
			(connect_pads
				(clearance 0)
			)
			(min_thickness 0.25)
			(keepout
				(tracks allowed)
				(vias not_allowed)
				(pads allowed)
				(copperpour not_allowed)
				(footprints allowed)
			)
			(placement
				(enabled no)
				(sheetname "")
			)
			(fill
				(thermal_gap 0.5)
				(thermal_bridge_width 0.5)
				(island_removal_mode 0)
			)
			(polygon
				(pts
					(xy 244.764306 -64.9224) (xy 244.764306 -65.4304) (xy 244.383306 -65.4304) (xy 244.383306 -64.9224)
				)
			)
		)
	)
	(footprint ""
		(layer "B.Cu")
		(at 460.388208 -132.842254 -90)
		(property "Reference" "R1M4"
			(at 0 0 90)
			(layer "B.SilkS")
			(hide yes)
			(effects
				(font
					(size 1.27 1.27)
				)
				(justify mirror)
			)
		)
		(property "Value" ""
			(at 0 0 90)
			(layer "B.Fab")
			(effects
				(font
					(size 1.27 1.27)
				)
				(justify mirror)
			)
		)
		(duplicate_pad_numbers_are_jumpers no)
		(fp_poly
			(pts
				(xy 0.2794 -0.1016) (xy -0.2794 -0.1016) (xy -0.2794 0.9906) (xy 0.2794 0.9906)
			)
			(stroke
				(width 0)
				(type default)
			)
			(fill no)
			(layer "B.CrtYd")
		)
		(fp_line
			(start -0.2794 0.9906)
			(end -0.2794 -0.1016)
			(stroke
				(width 0.1)
				(type default)
			)
			(layer "B.Fab")
		)
		(fp_line
			(start 0.2794 0.9906)
			(end -0.2794 0.9906)
			(stroke
				(width 0.1)
				(type default)
			)
			(layer "B.Fab")
		)
		(fp_line
			(start -0.2794 -0.1016)
			(end 0.2794 -0.1016)
			(stroke
				(width 0.1)
				(type default)
			)
			(layer "B.Fab")
		)
		(fp_line
			(start 0.2794 -0.1016)
			(end 0.2794 0.9906)
			(stroke
				(width 0.1)
				(type default)
			)
			(layer "B.Fab")
		)
		(pad "1" smd rect
			(at 0 0 90)
			(size 0.508 0.508)
			(layers "B.Cu" "B.Mask" "B.Paste")
			(net "PVCCIO_CPU0")
		)
		(pad "2" smd rect
			(at 0 0.889 90)
			(size 0.508 0.508)
			(layers "B.Cu" "B.Mask" "B.Paste")
			(net "XDP_CPU_PREQ_N")
		)
		(zone
			(layer "B.Cu")
			(hatch none 0.5)
			(connect_pads
				(clearance 0)
			)
			(min_thickness 0.25)
			(keepout
				(tracks not_allowed)
				(vias allowed)
				(pads allowed)
				(copperpour not_allowed)
				(footprints allowed)
			)
			(placement
				(enabled no)
				(sheetname "")
			)
			(fill
				(thermal_gap 0.5)
				(thermal_bridge_width 0.5)
				(island_removal_mode 0)
			)
			(polygon
				(pts
					(xy 459.753208 -132.588254) (xy 459.753208 -133.096254) (xy 460.134208 -133.096254) (xy 460.134208 -132.588254)
				)
			)
		)
		(zone
			(layer "B.Cu")
			(hatch none 0.5)
			(connect_pads
				(clearance 0)
			)
			(min_thickness 0.25)
			(keepout
				(tracks allowed)
				(vias not_allowed)
				(pads allowed)
				(copperpour not_allowed)
				(footprints allowed)
			)
			(placement
				(enabled no)
				(sheetname "")
			)
			(fill
				(thermal_gap 0.5)
				(thermal_bridge_width 0.5)
				(island_removal_mode 0)
			)
			(polygon
				(pts
					(xy 460.134208 -132.588254) (xy 460.134208 -133.096254) (xy 459.753208 -133.096254) (xy 459.753208 -132.588254)
				)
			)
		)
	)
	(footprint ""
		(layer "B.Cu")
		(at 466.852 -140.3604 90)
		(property "Reference" "C1L20"
			(at 0 0 90)
			(layer "B.SilkS")
			(hide yes)
			(effects
				(font
					(size 1.27 1.27)
				)
				(justify mirror)
			)
		)
		(property "Value" ""
			(at 0 0 90)
			(layer "B.Fab")
			(effects
				(font
					(size 1.27 1.27)
				)
				(justify mirror)
			)
		)
		(duplicate_pad_numbers_are_jumpers no)
		(fp_poly
			(pts
				(xy -0.3048 -0.1016) (xy -0.3048 0.9906) (xy 0.3048 0.9906) (xy 0.3048 -0.1016)
			)
			(stroke
				(width 0)
				(type default)
			)
			(fill no)
			(layer "B.CrtYd")
		)
		(fp_line
			(start 0.3048 -0.1016)
			(end 0.3048 0.9906)
			(stroke
				(width 0.1)
				(type default)
			)
			(layer "B.Fab")
		)
		(fp_line
			(start -0.3048 -0.1016)
			(end 0.3048 -0.1016)
			(stroke
				(width 0.1)
				(type default)
			)
			(layer "B.Fab")
		)
		(fp_line
			(start 0.3048 0.9906)
			(end -0.3048 0.9906)
			(stroke
				(width 0.1)
				(type default)
			)
			(layer "B.Fab")
		)
		(fp_line
			(start -0.3048 0.9906)
			(end -0.3048 -0.1016)
			(stroke
				(width 0.1)
				(type default)
			)
			(layer "B.Fab")
		)
		(pad "1" smd rect
			(at 0 0 270)
			(size 0.508 0.508)
			(layers "B.Cu" "B.Mask" "B.Paste")
			(net "P3V3_STBY")
		)
		(pad "2" smd rect
			(at 0 0.889 270)
			(size 0.508 0.508)
			(layers "B.Cu" "B.Mask" "B.Paste")
			(net "GND")
		)
		(zone
			(layer "B.Cu")
			(hatch none 0.5)
			(connect_pads
				(clearance 0)
			)
			(min_thickness 0.25)
			(keepout
				(tracks allowed)
				(vias not_allowed)
				(pads allowed)
				(copperpour not_allowed)
				(footprints allowed)
			)
			(placement
				(enabled no)
				(sheetname "")
			)
			(fill
				(thermal_gap 0.5)
				(thermal_bridge_width 0.5)
				(island_removal_mode 0)
			)
			(polygon
				(pts
					(xy 467.106 -140.6144) (xy 467.106 -140.1064) (xy 467.487 -140.1064) (xy 467.487 -140.6144)
				)
			)
		)
		(zone
			(layer "B.Cu")
			(hatch none 0.5)
			(connect_pads
				(clearance 0)
			)
			(min_thickness 0.25)
			(keepout
				(tracks not_allowed)
				(vias allowed)
				(pads allowed)
				(copperpour not_allowed)
				(footprints allowed)
			)
			(placement
				(enabled no)
				(sheetname "")
			)
			(fill
				(thermal_gap 0.5)
				(thermal_bridge_width 0.5)
				(island_removal_mode 0)
			)
			(polygon
				(pts
					(xy 467.487 -140.6144) (xy 467.487 -140.1064) (xy 467.106 -140.1064) (xy 467.106 -140.6144)
				)
			)
		)
	)
	(footprint ""
		(layer "B.Cu")
		(at 448.19189 -29.6164 -90)
		(property "Reference" "R1T30"
			(at 0 0 90)
			(layer "B.SilkS")
			(hide yes)
			(effects
				(font
					(size 1.27 1.27)
				)
				(justify mirror)
			)
		)
		(property "Value" ""
			(at 0 0 90)
			(layer "B.Fab")
			(effects
				(font
					(size 1.27 1.27)
				)
				(justify mirror)
			)
		)
		(duplicate_pad_numbers_are_jumpers no)
		(fp_poly
			(pts
				(xy 0.2794 -0.1016) (xy -0.2794 -0.1016) (xy -0.2794 0.9906) (xy 0.2794 0.9906)
			)
			(stroke
				(width 0)
				(type default)
			)
			(fill no)
			(layer "B.CrtYd")
		)
		(fp_line
			(start -0.2794 0.9906)
			(end -0.2794 -0.1016)
			(stroke
				(width 0.1)
				(type default)
			)
			(layer "B.Fab")
		)
		(fp_line
			(start 0.2794 0.9906)
			(end -0.2794 0.9906)
			(stroke
				(width 0.1)
				(type default)
			)
			(layer "B.Fab")
		)
		(fp_line
			(start -0.2794 -0.1016)
			(end 0.2794 -0.1016)
			(stroke
				(width 0.1)
				(type default)
			)
			(layer "B.Fab")
		)
		(fp_line
			(start 0.2794 -0.1016)
			(end 0.2794 0.9906)
			(stroke
				(width 0.1)
				(type default)
			)
			(layer "B.Fab")
		)
		(pad "1" smd rect
			(at 0 0 90)
			(size 0.508 0.508)
			(layers "B.Cu" "B.Mask" "B.Paste")
			(net "P1V2_AUX_BMC")
		)
		(pad "2" smd rect
			(at 0 0.889 90)
			(size 0.508 0.508)
			(layers "B.Cu" "B.Mask" "B.Paste")
			(net "BMC_M_VREFCA")
		)
		(zone
			(layer "B.Cu")
			(hatch none 0.5)
			(connect_pads
				(clearance 0)
			)
			(min_thickness 0.25)
			(keepout
				(tracks not_allowed)
				(vias allowed)
				(pads allowed)
				(copperpour not_allowed)
				(footprints allowed)
			)
			(placement
				(enabled no)
				(sheetname "")
			)
			(fill
				(thermal_gap 0.5)
				(thermal_bridge_width 0.5)
				(island_removal_mode 0)
			)
			(polygon
				(pts
					(xy 447.55689 -29.3624) (xy 447.55689 -29.8704) (xy 447.93789 -29.8704) (xy 447.93789 -29.3624)
				)
			)
		)
		(zone
			(layer "B.Cu")
			(hatch none 0.5)
			(connect_pads
				(clearance 0)
			)
			(min_thickness 0.25)
			(keepout
				(tracks allowed)
				(vias not_allowed)
				(pads allowed)
				(copperpour not_allowed)
				(footprints allowed)
			)
			(placement
				(enabled no)
				(sheetname "")
			)
			(fill
				(thermal_gap 0.5)
				(thermal_bridge_width 0.5)
				(island_removal_mode 0)
			)
			(polygon
				(pts
					(xy 447.93789 -29.3624) (xy 447.93789 -29.8704) (xy 447.55689 -29.8704) (xy 447.55689 -29.3624)
				)
			)
		)
	)
	(footprint ""
		(layer "B.Cu")
		(at 20.888706 -81.520792 -90)
		(property "Reference" "R9P13"
			(at 0 0 90)
			(layer "B.SilkS")
			(hide yes)
			(effects
				(font
					(size 1.27 1.27)
				)
				(justify mirror)
			)
		)
		(property "Value" "*"
			(at -0.064008 -4.108196 270)
			(unlocked yes)
			(layer "B.Fab")
			(hide yes)
			(effects
				(font
					(size 1.27 1.016)
					(thickness 0.1524)
				)
				(justify mirror)
			)
		)
		(property "Device Type" "270KR2F-GP_RCL_GP-270KR2F-GP,6A"
			(at -0.064008 -5.632196 270)
			(unlocked yes)
			(layer "B.Fab")
			(hide yes)
			(effects
				(font
					(size 1.27 1.016)
					(thickness 0.1524)
				)
				(justify mirror)
			)
		)
		(duplicate_pad_numbers_are_jumpers no)
		(fp_line
			(start -0.508 -0.9398)
			(end 0.508 -0.9398)
			(stroke
				(width 0.1524)
				(type default)
			)
			(layer "B.SilkS")
		)
		(fp_line
			(start 0.508 -0.9398)
			(end 0.508 0.9398)
			(stroke
				(width 0.1524)
				(type default)
			)
			(layer "B.SilkS")
		)
		(fp_rect
			(start 0.508 0.9398)
			(end -0.508 -0.9398)
			(stroke
				(width 0)
				(type default)
			)
			(fill no)
			(layer "B.CrtYd")
		)
		(fp_rect
			(start 0.508 0.9398)
			(end -0.508 -0.9398)
			(stroke
				(width 0)
				(type default)
			)
			(fill no)
			(layer "B.Fab")
		)
		(pad "1" smd custom
			(at 0 -0.4445 90)
			(size 0.1397 0.1397)
			(layers "B.Cu" "B.Mask" "B.Paste")
			(net "P12V_STBY")
			(options
				(clearance outline)
				(anchor circle)
			)
			(primitives
				(gr_poly
					(pts
						(arc
							(start -0.1778 0.2794)
							(mid -0.249642 0.249642)
							(end -0.2794 0.1778)
						)
						(arc
							(start -0.2794 -0.1778)
							(mid -0.249642 -0.249642)
							(end -0.1778 -0.2794)
						)
						(arc
							(start 0.1778 -0.2794)
							(mid 0.249642 -0.249642)
							(end 0.2794 -0.1778)
						)
						(arc
							(start 0.2794 0.1778)
							(mid 0.249642 0.249642)
							(end 0.1778 0.2794)
						)
					)
					(width 0)
					(fill yes)
				)
			)
		)
		(pad "2" smd custom
			(at 0 0.4445 90)
			(size 0.1397 0.1397)
			(layers "B.Cu" "B.Mask" "B.Paste")
			(net "A_P12V_STBY_FP_TRIGGER")
			(options
				(clearance outline)
				(anchor circle)
			)
			(primitives
				(gr_poly
					(pts
						(arc
							(start -0.1778 0.2794)
							(mid -0.249642 0.249642)
							(end -0.2794 0.1778)
						)
						(arc
							(start -0.2794 -0.1778)
							(mid -0.249642 -0.249642)
							(end -0.1778 -0.2794)
						)
						(arc
							(start 0.1778 -0.2794)
							(mid 0.249642 -0.249642)
							(end 0.2794 -0.1778)
						)
						(arc
							(start 0.2794 0.1778)
							(mid 0.249642 0.249642)
							(end 0.1778 0.2794)
						)
					)
					(width 0)
					(fill yes)
				)
			)
		)
	)
)
